# SCM (Grand Teton) — schematic netlist excerpt (pin names and nets, part order shuffled) for the footprints in the layout excerpt that follows; sources: Cadence DE-HDL packaged netlist, KiCad conversion of 12092022_DA0F0TMDCD0_F0T_Management_Board_D_brd_V3_OCP.brd

R105  Q_RES  0 5% CHIP  pkg 0402LF  page 36 : A = SMB_BMC_MM16_R4_SCL ; B = SMB_BMC_MM16_R5_SCL

(kicad_pcb
	(version 20260206)
	(generator "pcbnew")
	(generator_version "10.0")
	(general
		(thickness 1.6)
		(legacy_teardrops no)
	)
	(paper "A4")
	(title_block
		(title "12092022_DA0F0TMDCD0_F0T_Management_Board_D_brd_V3_OCP.brd")
		(comment 1 "Grand Teton / footprints 188-188 of 1440")
	)
	(layers
		(0 "F.Cu" signal "TOP")
		(4 "In1.Cu" signal "GND")
		(6 "In2.Cu" signal "IN1")
		(8 "In3.Cu" signal "GND1")
		(10 "In4.Cu" signal "IN2")
		(12 "In5.Cu" signal "VCC")
		(14 "In6.Cu" signal "VCC1")
		(16 "In7.Cu" signal "IN3")
		(18 "In8.Cu" signal "GND2")
		(20 "In9.Cu" signal "IN4")
		(22 "In10.Cu" signal "GND3")
		(2 "B.Cu" signal "BOTTOM")
		(9 "F.Adhes" user "F.Adhesive")
		(11 "B.Adhes" user "B.Adhesive")
		(13 "F.Paste" user "Package Geometry/Pastemask Top")
		(15 "B.Paste" user "Package Geometry/Pastemask Bottom")
		(5 "F.SilkS" user "Ref Des/Silkscreen Top")
		(7 "B.SilkS" user "Ref Des/Silkscreen Bottom")
		(1 "F.Mask" user "Board Geometry/Soldermask Top")
		(3 "B.Mask" user "Board Geometry/Soldermask Bottom")
		(17 "Dwgs.User" user "User.Drawings")
		(19 "Cmts.User" user "User.Comments")
		(21 "Eco1.User" user "User.Eco1")
		(23 "Eco2.User" user "User.Eco2")
		(25 "Edge.Cuts" user "Board Geometry/Outline")
		(27 "Margin" user)
		(31 "F.CrtYd" user "Package Geometry/Place Bound Top")
		(29 "B.CrtYd" user "Package Geometry/Place Bound Bottom")
		(35 "F.Fab" user "Ref Des/Assembly Top")
		(33 "B.Fab" user "Ref Des/Assembly Bottom")
	)
	(footprint ""
		(layer "F.Cu")
		(at 17.018 -102.743 90)
		(property "Reference" "R105"
			(at 0 0 90)
			(layer "F.SilkS")
			(hide yes)
			(effects
				(font
					(size 1.27 1.27)
				)
			)
		)
		(property "Value" ""
			(at 0 0 90)
			(layer "F.Fab")
			(effects
				(font
					(size 1.27 1.27)
				)
			)
		)
		(duplicate_pad_numbers_are_jumpers no)
		(fp_line
			(start 0.7874 -0.4064)
			(end 0.7874 0.4064)
			(stroke
				(width 0.1524)
				(type default)
			)
			(layer "F.SilkS")
		)
		(fp_line
			(start -0.7874 -0.4064)
			(end 0.7874 -0.4064)
			(stroke
				(width 0.1524)
				(type default)
			)
			(layer "F.SilkS")
		)
		(fp_line
			(start 0.7874 0.4064)
			(end -0.7874 0.4064)
			(stroke
				(width 0.1524)
				(type default)
			)
			(layer "F.SilkS")
		)
		(fp_line
			(start -0.7874 0.4064)
			(end -0.7874 -0.4064)
			(stroke
				(width 0.1524)
				(type default)
			)
			(layer "F.SilkS")
		)
		(fp_line
			(start -0.12065 -0.305054)
			(end -0.12065 -0.2794)
			(stroke
				(width 0.1)
				(type default)
			)
			(layer "F.Fab")
		)
		(fp_line
			(start -0.67945 -0.305054)
			(end -0.12065 -0.305054)
			(stroke
				(width 0.1)
				(type default)
			)
			(layer "F.Fab")
		)
		(fp_line
			(start 0.67945 -0.3048)
			(end 0.67945 0.3048)
			(stroke
				(width 0.1)
				(type default)
			)
			(layer "F.Fab")
		)
		(fp_line
			(start 0.12065 -0.3048)
			(end 0.67945 -0.3048)
			(stroke
				(width 0.1)
				(type default)
			)
			(layer "F.Fab")
		)
		(fp_line
			(start 0.12065 -0.2794)
			(end 0.12065 -0.3048)
			(stroke
				(width 0.1)
				(type default)
			)
			(layer "F.Fab")
		)
		(fp_line
			(start -0.12065 -0.2794)
			(end 0.12065 -0.2794)
			(stroke
				(width 0.1)
				(type default)
			)
			(layer "F.Fab")
		)
		(fp_line
			(start 0.120396 0.2794)
			(end -0.12065 0.2794)
			(stroke
				(width 0.1)
				(type default)
			)
			(layer "F.Fab")
		)
		(fp_line
			(start -0.12065 0.2794)
			(end -0.12065 0.3048)
			(stroke
				(width 0.1)
				(type default)
			)
			(layer "F.Fab")
		)
		(fp_line
			(start 0.67945 0.3048)
			(end 0.120396 0.3048)
			(stroke
				(width 0.1)
				(type default)
			)
			(layer "F.Fab")
		)
		(fp_line
			(start 0.120396 0.3048)
			(end 0.120396 0.2794)
			(stroke
				(width 0.1)
				(type default)
			)
			(layer "F.Fab")
		)
		(fp_line
			(start -0.12065 0.3048)
			(end -0.67945 0.3048)
			(stroke
				(width 0.1)
				(type default)
			)
			(layer "F.Fab")
		)
		(fp_line
			(start -0.67945 0.3048)
			(end -0.67945 -0.305054)
			(stroke
				(width 0.1)
				(type default)
			)
			(layer "F.Fab")
		)
		(pad "1" smd circle
			(at -0.40005 0 90)
			(size 0 0)
			(layers "F.Cu" "F.Mask" "F.Paste")
			(net "SMB_BMC_MM16_R4_SCL")
		)
		(pad "2" smd circle
			(at 0.40005 0 90)
			(size 0 0)
			(layers "F.Cu" "F.Mask" "F.Paste")
			(net "SMB_BMC_MM16_R5_SCL")
		)
	)
)
